(kicad_pcb
	(version 20241229)
	(generator "pcbnew")
	(generator_version "9.0")
	(general
		(thickness 1.6642)
		(legacy_teardrops no)
	)
	(paper "A3")
	(title_block
		(title "PolarFire SoM")
		(date "2025-07-22")
		(rev "1.1.4")
		(company "Antmicro Ltd")
		(comment 1 "www.antmicro.com")
		(comment 9 "footprint 70 of 470 (U2), pads 83-153 of 153")
	)
	(layers
		(0 "F.Cu" mixed)
		(4 "In1.Cu" power)
		(6 "In2.Cu" signal)
		(8 "In3.Cu" power)
		(10 "In4.Cu" signal)
		(12 "In5.Cu" power)
		(14 "In6.Cu" power)
		(16 "In7.Cu" signal)
		(18 "In8.Cu" power)
		(20 "In9.Cu" signal)
		(22 "In10.Cu" power)
		(24 "In11.Cu" signal)
		(26 "In12.Cu" signal)
		(2 "B.Cu" mixed)
		(9 "F.Adhes" user "F.Adhesive")
		(11 "B.Adhes" user "B.Adhesive")
		(13 "F.Paste" user)
		(15 "B.Paste" user)
		(5 "F.SilkS" user "F.Silkscreen")
		(7 "B.SilkS" user "B.Silkscreen")
		(1 "F.Mask" user)
		(3 "B.Mask" user)
		(17 "Dwgs.User" user "User.Drawings")
		(19 "Cmts.User" user "User.Comments")
		(21 "Eco1.User" user "User.Eco1")
		(23 "Eco2.User" user "User.Eco2")
		(25 "Edge.Cuts" user)
		(27 "Margin" user)
		(31 "F.CrtYd" user "F.Courtyard")
		(29 "B.CrtYd" user "B.Courtyard")
		(35 "F.Fab" user)
		(33 "B.Fab" user)
	)
	(footprint "antmicro-footprints:BGA-196-153_11.5x13mm_Layout14x14_P0.5x0.5mm"
		(layer "F.Cu")
		(at 214.6935 131.7)
		(property "Reference" "U2"
			(at -5.9435 -5.1 90)
			(layer "F.SilkS")
			(effects
				(font
					(size 0.7 0.7)
					(thickness 0.15)
				)
				(justify left bottom)
			)
		)
		(property "Value" "SDINBDG4-8G"
			(at 0 7.6 0)
			(layer "F.Fab")
			(hide yes)
			(effects
				(font
					(size 0.7 0.7)
					(thickness 0.15)
				)
				(justify left bottom)
			)
		)
		(property "Datasheet" "https://www.infineon.com/dgdl/Infineon-AN98491_Recommended_PCB_Routing_Guidelines_for_a_Infineon_e.MMC_Memory_Device-ApplicationNotes-v05_00-EN.pdf?fileId=8ac78c8c7d718a49017d71baea97084d"
			(at 0 0 0)
			(layer "F.Fab")
			(hide yes)
			(effects
				(font
					(size 1.27 1.27)
					(thickness 0.15)
				)
			)
		)
		(property "Description" "NAND Flash Serial e-MMC 64G-bit SanDisk iNAND 7250 Industrial emmc"
			(at 0 0 0)
			(layer "F.Fab")
			(hide yes)
			(effects
				(font
					(size 1.27 1.27)
					(thickness 0.15)
				)
			)
		)
		(property "Author" "Antmicro"
			(at 0 0 0)
			(layer "F.Fab")
			(hide yes)
			(effects
				(font
					(size 1 1)
					(thickness 0.15)
				)
			)
		)
		(property "License" "Apache-2.0"
			(at 0 0 0)
			(layer "F.Fab")
			(hide yes)
			(effects
				(font
					(size 1 1)
					(thickness 0.15)
				)
			)
		)
		(property "MPN" "SDINBDG4-8G"
			(at 0 0 0)
			(layer "F.Fab")
			(hide yes)
			(effects
				(font
					(size 1 1)
					(thickness 0.15)
				)
			)
		)
		(property "Manufacturer" "SanDisk"
			(at 0 0 0)
			(layer "F.Fab")
			(hide yes)
			(effects
				(font
					(size 1 1)
					(thickness 0.15)
				)
			)
		)
		(property "VSD_class" "eMMC"
			(at 0 0 0)
			(layer "F.Fab")
			(hide yes)
			(effects
				(font
					(size 1 1)
					(thickness 0.15)
				)
			)
		)
		(sheetname "/Memory/")
		(sheetfile "memory.kicad_sch")
		(attr smd)
		(pad "H12" smd circle
			(at 2.249 0.247)
			(size 0.245 0.245)
			(layers "F.Cu" "F.Mask" "F.Paste")
			(net 719 "unconnected-(U2B-NC-PadH12)")
			(pinfunction "NC")
			(pintype "free")
		)
		(pad "H13" smd circle
			(at 2.749 0.247)
			(size 0.245 0.245)
			(layers "F.Cu" "F.Mask" "F.Paste")
			(net 680 "unconnected-(U2B-NC-PadH13)")
			(pinfunction "NC")
			(pintype "free")
		)
		(pad "H14" smd circle
			(at 3.249 0.247)
			(size 0.245 0.245)
			(layers "F.Cu" "F.Mask" "F.Paste")
			(net 768 "unconnected-(U2B-NC-PadH14)")
			(pinfunction "NC")
			(pintype "free")
		)
		(pad "J1" smd circle
			(at -3.25 0.747)
			(size 0.245 0.245)
			(layers "F.Cu" "F.Mask" "F.Paste")
			(net 757 "unconnected-(U2B-NC-PadJ1)")
			(pinfunction "NC")
			(pintype "free")
		)
		(pad "J2" smd circle
			(at -2.75 0.747)
			(size 0.245 0.245)
			(layers "F.Cu" "F.Mask" "F.Paste")
			(net 708 "unconnected-(U2B-NC-PadJ2)")
			(pinfunction "NC")
			(pintype "free")
		)
		(pad "J3" smd circle
			(at -2.25 0.747)
			(size 0.245 0.245)
			(layers "F.Cu" "F.Mask" "F.Paste")
			(net 749 "unconnected-(U2B-NC-PadJ3)")
			(pinfunction "NC")
			(pintype "free")
		)
		(pad "J5" smd circle
			(at -1.25 0.747)
			(size 0.245 0.245)
			(layers "F.Cu" "F.Mask" "F.Paste")
			(net 417 "GND")
			(pinfunction "VSS")
			(pintype "passive")
		)
		(pad "J10" smd circle
			(at 1.249 0.747)
			(size 0.245 0.245)
			(layers "F.Cu" "F.Mask" "F.Paste")
			(net 50 "+3V3")
			(pinfunction "VCC")
			(pintype "passive")
		)
		(pad "J12" smd circle
			(at 2.249 0.747)
			(size 0.245 0.245)
			(layers "F.Cu" "F.Mask" "F.Paste")
			(net 764 "unconnected-(U2B-NC-PadJ12)")
			(pinfunction "NC")
			(pintype "free")
		)
		(pad "J13" smd circle
			(at 2.749 0.747)
			(size 0.245 0.245)
			(layers "F.Cu" "F.Mask" "F.Paste")
			(net 750 "unconnected-(U2B-NC-PadJ13)")
			(pinfunction "NC")
			(pintype "free")
		)
		(pad "J14" smd circle
			(at 3.249 0.747)
			(size 0.245 0.245)
			(layers "F.Cu" "F.Mask" "F.Paste")
			(net 718 "unconnected-(U2B-NC-PadJ14)")
			(pinfunction "NC")
			(pintype "free")
		)
		(pad "K1" smd circle
			(at -3.25 1.249)
			(size 0.245 0.245)
			(layers "F.Cu" "F.Mask" "F.Paste")
			(net 677 "unconnected-(U2B-NC-PadK1)")
			(pinfunction "NC")
			(pintype "free")
		)
		(pad "K2" smd circle
			(at -2.75 1.249)
			(size 0.245 0.245)
			(layers "F.Cu" "F.Mask" "F.Paste")
			(net 662 "unconnected-(U2B-NC-PadK2)")
			(pinfunction "NC")
			(pintype "free")
		)
		(pad "K3" smd circle
			(at -2.25 1.249)
			(size 0.245 0.245)
			(layers "F.Cu" "F.Mask" "F.Paste")
			(net 686 "unconnected-(U2B-NC-PadK3)")
			(pinfunction "NC")
			(pintype "free")
		)
		(pad "K5" smd circle
			(at -1.25 1.249)
			(size 0.245 0.245)
			(layers "F.Cu" "F.Mask" "F.Paste")
			(net 387 "/FPGA MSSIO/EMMC.RST_n")
			(pinfunction "RST_N")
			(pintype "input")
		)
		(pad "K6" smd circle
			(at -0.75 1.249)
			(size 0.245 0.245)
			(layers "F.Cu" "F.Mask" "F.Paste")
			(net 748 "unconnected-(U2A-RFU-PadK6)")
			(pinfunction "RFU")
			(pintype "no_connect")
		)
		(pad "K7" smd circle
			(at -0.25 1.249)
			(size 0.245 0.245)
			(layers "F.Cu" "F.Mask" "F.Paste")
			(net 657 "unconnected-(U2A-RFU-PadK7)")
			(pinfunction "RFU")
			(pintype "no_connect")
		)
		(pad "K8" smd circle
			(at 0.247 1.249)
			(size 0.245 0.245)
			(layers "F.Cu" "F.Mask" "F.Paste")
			(net 417 "GND")
			(pinfunction "VSS")
			(pintype "passive")
		)
		(pad "K9" smd circle
			(at 0.747 1.249)
			(size 0.245 0.245)
			(layers "F.Cu" "F.Mask" "F.Paste")
			(net 50 "+3V3")
			(pinfunction "VCC")
			(pintype "passive")
		)
		(pad "K10" smd circle
			(at 1.249 1.249)
			(size 0.245 0.245)
			(layers "F.Cu" "F.Mask" "F.Paste")
			(net 712 "unconnected-(U2A-RFU-PadK10)")
			(pinfunction "RFU")
			(pintype "no_connect")
		)
		(pad "K12" smd circle
			(at 2.249 1.249)
			(size 0.245 0.245)
			(layers "F.Cu" "F.Mask" "F.Paste")
			(net 767 "unconnected-(U2B-NC-PadK12)")
			(pinfunction "NC")
			(pintype "free")
		)
		(pad "K13" smd circle
			(at 2.749 1.249)
			(size 0.245 0.245)
			(layers "F.Cu" "F.Mask" "F.Paste")
			(net 754 "unconnected-(U2B-NC-PadK13)")
			(pinfunction "NC")
			(pintype "free")
		)
		(pad "K14" smd circle
			(at 3.249 1.249)
			(size 0.245 0.245)
			(layers "F.Cu" "F.Mask" "F.Paste")
			(net 724 "unconnected-(U2B-NC-PadK14)")
			(pinfunction "NC")
			(pintype "free")
		)
		(pad "L1" smd circle
			(at -3.25 1.749)
			(size 0.245 0.245)
			(layers "F.Cu" "F.Mask" "F.Paste")
			(net 727 "unconnected-(U2B-NC-PadL1)")
			(pinfunction "NC")
			(pintype "free")
		)
		(pad "L2" smd circle
			(at -2.75 1.749)
			(size 0.245 0.245)
			(layers "F.Cu" "F.Mask" "F.Paste")
			(net 702 "unconnected-(U2B-NC-PadL2)")
			(pinfunction "NC")
			(pintype "free")
		)
		(pad "L3" smd circle
			(at -2.25 1.749)
			(size 0.245 0.245)
			(layers "F.Cu" "F.Mask" "F.Paste")
			(net 696 "unconnected-(U2B-NC-PadL3)")
			(pinfunction "NC")
			(pintype "free")
		)
		(pad "L12" smd circle
			(at 2.249 1.749)
			(size 0.245 0.245)
			(layers "F.Cu" "F.Mask" "F.Paste")
			(net 751 "unconnected-(U2B-NC-PadL12)")
			(pinfunction "NC")
			(pintype "free")
		)
		(pad "L13" smd circle
			(at 2.749 1.749)
			(size 0.245 0.245)
			(layers "F.Cu" "F.Mask" "F.Paste")
			(net 726 "unconnected-(U2B-NC-PadL13)")
			(pinfunction "NC")
			(pintype "free")
		)
		(pad "L14" smd circle
			(at 3.249 1.749)
			(size 0.245 0.245)
			(layers "F.Cu" "F.Mask" "F.Paste")
			(net 683 "unconnected-(U2B-NC-PadL14)")
			(pinfunction "NC")
			(pintype "free")
		)
		(pad "M1" smd circle
			(at -3.25 2.249)
			(size 0.245 0.245)
			(layers "F.Cu" "F.Mask" "F.Paste")
			(net 703 "unconnected-(U2B-NC-PadM1)")
			(pinfunction "NC")
			(pintype "free")
		)
		(pad "M2" smd circle
			(at -2.75 2.249)
			(size 0.245 0.245)
			(layers "F.Cu" "F.Mask" "F.Paste")
			(net 667 "unconnected-(U2B-NC-PadM2)")
			(pinfunction "NC")
			(pintype "free")
		)
		(pad "M3" smd circle
			(at -2.25 2.249)
			(size 0.245 0.245)
			(layers "F.Cu" "F.Mask" "F.Paste")
			(net 720 "unconnected-(U2B-NC-PadM3)")
			(pinfunction "NC")
			(pintype "free")
		)
		(pad "M4" smd circle
			(at -1.75 2.249)
			(size 0.245 0.245)
			(layers "F.Cu" "F.Mask" "F.Paste")
			(net 137 "SD_VDD")
			(pinfunction "VCCQ")
			(pintype "passive")
		)
		(pad "M5" smd circle
			(at -1.25 2.249)
			(size 0.245 0.245)
			(layers "F.Cu" "F.Mask" "F.Paste")
			(net 391 "/FPGA MSSIO/EMMC.CMD")
			(pinfunction "CMD")
			(pintype "bidirectional")
		)
		(pad "M6" smd circle
			(at -0.75 2.249)
			(size 0.245 0.245)
			(layers "F.Cu" "F.Mask" "F.Paste")
			(net 264 "/FPGA MSSIO/EMMC.CLK")
			(pinfunction "CLK")
			(pintype "input")
		)
		(pad "M7" smd circle
			(at -0.25 2.249)
			(size 0.245 0.245)
			(layers "F.Cu" "F.Mask" "F.Paste")
			(net 476 "unconnected-(U2B-NC-PadM7)")
			(pinfunction "NC")
			(pintype "free")
		)
		(pad "M8" smd circle
			(at 0.247 2.249)
			(size 0.245 0.245)
			(layers "F.Cu" "F.Mask" "F.Paste")
			(net 707 "unconnected-(U2B-NC-PadM8)")
			(pinfunction "NC")
			(pintype "free")
		)
		(pad "M9" smd circle
			(at 0.747 2.249)
			(size 0.245 0.245)
			(layers "F.Cu" "F.Mask" "F.Paste")
			(net 682 "unconnected-(U2B-NC-PadM9)")
			(pinfunction "NC")
			(pintype "free")
		)
		(pad "M10" smd circle
			(at 1.249 2.249)
			(size 0.245 0.245)
			(layers "F.Cu" "F.Mask" "F.Paste")
			(net 755 "unconnected-(U2B-NC-PadM10)")
			(pinfunction "NC")
			(pintype "free")
		)
		(pad "M11" smd circle
			(at 1.749 2.249)
			(size 0.245 0.245)
			(layers "F.Cu" "F.Mask" "F.Paste")
			(net 681 "unconnected-(U2B-NC-PadM11)")
			(pinfunction "NC")
			(pintype "free")
		)
		(pad "M12" smd circle
			(at 2.249 2.249)
			(size 0.245 0.245)
			(layers "F.Cu" "F.Mask" "F.Paste")
			(net 760 "unconnected-(U2B-NC-PadM12)")
			(pinfunction "NC")
			(pintype "free")
		)
		(pad "M13" smd circle
			(at 2.749 2.249)
			(size 0.245 0.245)
			(layers "F.Cu" "F.Mask" "F.Paste")
			(net 693 "unconnected-(U2B-NC-PadM13)")
			(pinfunction "NC")
			(pintype "free")
		)
		(pad "M14" smd circle
			(at 3.249 2.249)
			(size 0.245 0.245)
			(layers "F.Cu" "F.Mask" "F.Paste")
			(net 761 "unconnected-(U2B-NC-PadM14)")
			(pinfunction "NC")
			(pintype "free")
		)
		(pad "N1" smd circle
			(at -3.25 2.749)
			(size 0.245 0.245)
			(layers "F.Cu" "F.Mask" "F.Paste")
			(net 672 "unconnected-(U2B-NC-PadN1)")
			(pinfunction "NC")
			(pintype "free")
		)
		(pad "N2" smd circle
			(at -2.75 2.749)
			(size 0.245 0.245)
			(layers "F.Cu" "F.Mask" "F.Paste")
			(net 417 "GND")
			(pinfunction "VSSQ")
			(pintype "passive")
		)
		(pad "N3" smd circle
			(at -2.25 2.749)
			(size 0.245 0.245)
			(layers "F.Cu" "F.Mask" "F.Paste")
			(net 721 "unconnected-(U2B-NC-PadN3)")
			(pinfunction "NC")
			(pintype "free")
		)
		(pad "N4" smd circle
			(at -1.75 2.749)
			(size 0.245 0.245)
			(layers "F.Cu" "F.Mask" "F.Paste")
			(net 137 "SD_VDD")
			(pinfunction "VCCQ")
			(pintype "passive")
		)
		(pad "N5" smd circle
			(at -1.25 2.749)
			(size 0.245 0.245)
			(layers "F.Cu" "F.Mask" "F.Paste")
			(net 417 "GND")
			(pinfunction "VSSQ")
			(pintype "passive")
		)
		(pad "N6" smd circle
			(at -0.75 2.749)
			(size 0.245 0.245)
			(layers "F.Cu" "F.Mask" "F.Paste")
			(net 691 "unconnected-(U2B-NC-PadN6)")
			(pinfunction "NC")
			(pintype "free")
		)
		(pad "N7" smd circle
			(at -0.25 2.749)
			(size 0.245 0.245)
			(layers "F.Cu" "F.Mask" "F.Paste")
			(net 687 "unconnected-(U2B-NC-PadN7)")
			(pinfunction "NC")
			(pintype "free")
		)
		(pad "N8" smd circle
			(at 0.247 2.749)
			(size 0.245 0.245)
			(layers "F.Cu" "F.Mask" "F.Paste")
			(net 739 "unconnected-(U2B-NC-PadN8)")
			(pinfunction "NC")
			(pintype "free")
		)
		(pad "N9" smd circle
			(at 0.747 2.749)
			(size 0.245 0.245)
			(layers "F.Cu" "F.Mask" "F.Paste")
			(net 769 "unconnected-(U2B-NC-PadN9)")
			(pinfunction "NC")
			(pintype "free")
		)
		(pad "N10" smd circle
			(at 1.249 2.749)
			(size 0.245 0.245)
			(layers "F.Cu" "F.Mask" "F.Paste")
			(net 735 "unconnected-(U2B-NC-PadN10)")
			(pinfunction "NC")
			(pintype "free")
		)
		(pad "N11" smd circle
			(at 1.749 2.749)
			(size 0.245 0.245)
			(layers "F.Cu" "F.Mask" "F.Paste")
			(net 679 "unconnected-(U2B-NC-PadN11)")
			(pinfunction "NC")
			(pintype "free")
		)
		(pad "N12" smd circle
			(at 2.249 2.749)
			(size 0.245 0.245)
			(layers "F.Cu" "F.Mask" "F.Paste")
			(net 740 "unconnected-(U2B-NC-PadN12)")
			(pinfunction "NC")
			(pintype "free")
		)
		(pad "N13" smd circle
			(at 2.749 2.749)
			(size 0.245 0.245)
			(layers "F.Cu" "F.Mask" "F.Paste")
			(net 717 "unconnected-(U2B-NC-PadN13)")
			(pinfunction "NC")
			(pintype "free")
		)
		(pad "N14" smd circle
			(at 3.249 2.749)
			(size 0.245 0.245)
			(layers "F.Cu" "F.Mask" "F.Paste")
			(net 732 "unconnected-(U2B-NC-PadN14)")
			(pinfunction "NC")
			(pintype "free")
		)
		(pad "P1" smd circle
			(at -3.25 3.249)
			(size 0.245 0.245)
			(layers "F.Cu" "F.Mask" "F.Paste")
			(net 697 "unconnected-(U2B-NC-PadP1)")
			(pinfunction "NC")
			(pintype "free")
		)
		(pad "P2" smd circle
			(at -2.75 3.249)
			(size 0.245 0.245)
			(layers "F.Cu" "F.Mask" "F.Paste")
			(net 473 "unconnected-(U2B-NC-PadP2)")
			(pinfunction "NC")
			(pintype "free")
		)
		(pad "P3" smd circle
			(at -2.25 3.249)
			(size 0.245 0.245)
			(layers "F.Cu" "F.Mask" "F.Paste")
			(net 137 "SD_VDD")
			(pinfunction "VCCQ")
			(pintype "passive")
		)
		(pad "P4" smd circle
			(at -1.75 3.249)
			(size 0.245 0.245)
			(layers "F.Cu" "F.Mask" "F.Paste")
			(net 417 "GND")
			(pinfunction "VSSQ")
			(pintype "passive")
		)
		(pad "P5" smd circle
			(at -1.25 3.249)
			(size 0.245 0.245)
			(layers "F.Cu" "F.Mask" "F.Paste")
			(net 137 "SD_VDD")
			(pinfunction "VCCQ")
			(pintype "passive")
		)
		(pad "P6" smd circle
			(at -0.75 3.249)
			(size 0.245 0.245)
			(layers "F.Cu" "F.Mask" "F.Paste")
			(net 417 "GND")
			(pinfunction "VSSQ")
			(pintype "passive")
		)
		(pad "P7" smd circle
			(at -0.25 3.249)
			(size 0.245 0.245)
			(layers "F.Cu" "F.Mask" "F.Paste")
			(net 725 "unconnected-(U2A-RFU-PadP7)")
			(pinfunction "RFU")
			(pintype "no_connect")
		)
		(pad "P8" smd circle
			(at 0.247 3.249)
			(size 0.245 0.245)
			(layers "F.Cu" "F.Mask" "F.Paste")
			(net 706 "unconnected-(U2B-NC-PadP8)")
			(pinfunction "NC")
			(pintype "free")
		)
		(pad "P9" smd circle
			(at 0.747 3.249)
			(size 0.245 0.245)
			(layers "F.Cu" "F.Mask" "F.Paste")
			(net 704 "unconnected-(U2B-NC-PadP9)")
			(pinfunction "NC")
			(pintype "free")
		)
		(pad "P10" smd circle
			(at 1.249 3.249)
			(size 0.245 0.245)
			(layers "F.Cu" "F.Mask" "F.Paste")
			(net 728 "unconnected-(U2A-RFU-PadP10)")
			(pinfunction "RFU")
			(pintype "no_connect")
		)
		(pad "P11" smd circle
			(at 1.749 3.249)
			(size 0.245 0.245)
			(layers "F.Cu" "F.Mask" "F.Paste")
			(net 744 "unconnected-(U2B-NC-PadP11)")
			(pinfunction "NC")
			(pintype "free")
		)
		(pad "P12" smd circle
			(at 2.249 3.249)
			(size 0.245 0.245)
			(layers "F.Cu" "F.Mask" "F.Paste")
			(net 658 "unconnected-(U2B-NC-PadP12)")
			(pinfunction "NC")
			(pintype "free")
		)
		(pad "P13" smd circle
			(at 2.749 3.249)
			(size 0.245 0.245)
			(layers "F.Cu" "F.Mask" "F.Paste")
			(net 747 "unconnected-(U2B-NC-PadP13)")
			(pinfunction "NC")
			(pintype "free")
		)
		(pad "P14" smd circle
			(at 3.249 3.249)
			(size 0.245 0.245)
			(layers "F.Cu" "F.Mask" "F.Paste")
			(net 752 "unconnected-(U2B-NC-PadP14)")
			(pinfunction "NC")
			(pintype "free")
		)
	)
)
